(kicad_pcb
	(version 20260206)
	(generator "pcbnew")
	(generator_version "10.0")
	(general
		(thickness 1.6)
		(legacy_teardrops no)
	)
	(paper "A4")
	(title_block
		(title "pdpb — Lightning_PDPB_BRD.brd")
		(comment 1 "Lightning (Wiwynn / Facebook NVMe JBOF) / footprints 766-772 of 1140")
	)
	(layers
		(0 "F.Cu" signal "TOP")
		(4 "In1.Cu" signal "L2GND")
		(6 "In2.Cu" signal "L3")
		(8 "In3.Cu" signal "L4VCC")
		(10 "In4.Cu" signal "L5VCC")
		(12 "In5.Cu" signal "L6")
		(14 "In6.Cu" signal "L7GND")
		(2 "B.Cu" signal "BOTTOM")
		(9 "F.Adhes" user "F.Adhesive")
		(11 "B.Adhes" user "B.Adhesive")
		(13 "F.Paste" user "Package Geometry/Pastemask Top")
		(15 "B.Paste" user "Package Geometry/Pastemask Bottom")
		(5 "F.SilkS" user "Ref Des/Silkscreen Top")
		(7 "B.SilkS" user "Ref Des/Silkscreen Bottom")
		(1 "F.Mask" user "Board Geometry/Soldermask Top")
		(3 "B.Mask" user "Board Geometry/Soldermask Bottom")
		(17 "Dwgs.User" user "User.Drawings")
		(19 "Cmts.User" user "User.Comments")
		(21 "Eco1.User" user "User.Eco1")
		(23 "Eco2.User" user "User.Eco2")
		(25 "Edge.Cuts" user "Board Geometry/Outline")
		(27 "Margin" user)
		(31 "F.CrtYd" user "Package Geometry/Place Bound Top")
		(29 "B.CrtYd" user "Package Geometry/Place Bound Bottom")
		(35 "F.Fab" user "Ref Des/Assembly Top")
		(33 "B.Fab" user "Ref Des/Assembly Bottom")
	)
	(footprint ""
		(layer "F.Cu")
		(at 38.0746 -414.8074)
		(property "Reference" "Q18"
			(at 0 0 0)
			(layer "F.SilkS")
			(hide yes)
			(effects
				(font
					(size 1.27 1.27)
				)
			)
		)
		(property "Value" "2N7002A-7-GP"
			(at 0.127 -8.9662 0)
			(unlocked yes)
			(layer "F.Fab")
			(hide yes)
			(effects
				(font
					(size 1.016 1.016)
					(thickness 0.1524)
				)
			)
		)
		(property "Device Type" "SOT23DGS2D4H48"
			(at 0.127 -10.4902 0)
			(unlocked yes)
			(layer "F.Fab")
			(hide yes)
			(effects
				(font
					(size 1.016 1.016)
					(thickness 0.1524)
				)
			)
		)
		(duplicate_pad_numbers_are_jumpers no)
		(fp_line
			(start -1.651 -1.778)
			(end -1.651 1.778)
			(stroke
				(width 0.1524)
				(type default)
			)
			(layer "F.SilkS")
		)
		(fp_line
			(start -1.651 1.778)
			(end 1.651 1.778)
			(stroke
				(width 0.1524)
				(type default)
			)
			(layer "F.SilkS")
		)
		(fp_line
			(start 1.651 -1.778)
			(end -1.651 -1.778)
			(stroke
				(width 0.1524)
				(type default)
			)
			(layer "F.SilkS")
		)
		(fp_line
			(start 1.651 1.778)
			(end 1.651 -1.778)
			(stroke
				(width 0.1524)
				(type default)
			)
			(layer "F.SilkS")
		)
		(fp_poly
			(pts
				(xy -1.778 1.8796) (xy -1.778 -1.8796) (xy 1.778 -1.8796) (xy 1.778 1.8796)
			)
			(stroke
				(width 0)
				(type default)
			)
			(fill no)
			(layer "F.CrtYd")
		)
		(fp_poly
			(pts
				(xy -1.778 1.8796) (xy -1.778 -1.8796) (xy 1.778 -1.8796) (xy 1.778 1.8796)
			)
			(stroke
				(width 0)
				(type default)
			)
			(fill no)
			(layer "F.Fab")
		)
		(pad "D" smd custom
			(at 0 -0.9525)
			(size 0.1905 0.1905)
			(layers "F.Cu" "F.Mask" "F.Paste")
			(net "SW_SSD10_R")
			(options
				(clearance outline)
				(anchor circle)
			)
			(primitives
				(gr_poly
					(pts
						(arc
							(start -0.1778 0.5715)
							(mid -0.321484 0.511984)
							(end -0.381 0.3683)
						)
						(arc
							(start -0.381 -0.3683)
							(mid -0.321484 -0.511984)
							(end -0.1778 -0.5715)
						)
						(arc
							(start 0.1778 -0.5715)
							(mid 0.321484 -0.511984)
							(end 0.381 -0.3683)
						)
						(arc
							(start 0.381 0.3683)
							(mid 0.321484 0.511984)
							(end 0.1778 0.5715)
						)
					)
					(width 0)
					(fill yes)
				)
			)
		)
		(pad "G" smd custom
			(at -0.98425 0.9525)
			(size 0.1905 0.1905)
			(layers "F.Cu" "F.Mask" "F.Paste")
			(net "SSD10_PWREN")
			(options
				(clearance outline)
				(anchor circle)
			)
			(primitives
				(gr_poly
					(pts
						(arc
							(start -0.1778 0.5715)
							(mid -0.321484 0.511984)
							(end -0.381 0.3683)
						)
						(arc
							(start -0.381 -0.3683)
							(mid -0.321484 -0.511984)
							(end -0.1778 -0.5715)
						)
						(arc
							(start 0.1778 -0.5715)
							(mid 0.321484 -0.511984)
							(end 0.381 -0.3683)
						)
						(arc
							(start 0.381 0.3683)
							(mid 0.321484 0.511984)
							(end 0.1778 0.5715)
						)
					)
					(width 0)
					(fill yes)
				)
			)
		)
		(pad "S" smd custom
			(at 0.98425 0.9525)
			(size 0.1905 0.1905)
			(layers "F.Cu" "F.Mask" "F.Paste")
			(net "GND")
			(options
				(clearance outline)
				(anchor circle)
			)
			(primitives
				(gr_poly
					(pts
						(arc
							(start -0.1778 0.5715)
							(mid -0.321484 0.511984)
							(end -0.381 0.3683)
						)
						(arc
							(start -0.381 -0.3683)
							(mid -0.321484 -0.511984)
							(end -0.1778 -0.5715)
						)
						(arc
							(start 0.1778 -0.5715)
							(mid 0.321484 -0.511984)
							(end 0.381 -0.3683)
						)
						(arc
							(start 0.381 0.3683)
							(mid 0.321484 0.511984)
							(end 0.1778 0.5715)
						)
					)
					(width 0)
					(fill yes)
				)
			)
		)
	)
	(footprint ""
		(layer "F.Cu")
		(at 94.996 -197.358 180)
		(property "Reference" "R9596"
			(at 0 0 180)
			(layer "F.SilkS")
			(hide yes)
			(effects
				(font
					(size 1.27 1.27)
				)
			)
		)
		(property "Value" "10R2F-L-GP"
			(at 0.064008 -3.993896 180)
			(unlocked yes)
			(layer "F.Fab")
			(hide yes)
			(effects
				(font
					(size 1.016 1.016)
					(thickness 0.1524)
				)
			)
		)
		(property "Device Type" "R402H14"
			(at 0.064008 -5.517896 180)
			(unlocked yes)
			(layer "F.Fab")
			(hide yes)
			(effects
				(font
					(size 1.016 1.016)
					(thickness 0.1524)
				)
			)
		)
		(duplicate_pad_numbers_are_jumpers no)
		(fp_line
			(start 0.508 -0.9398)
			(end -0.508 -0.9398)
			(stroke
				(width 0.1524)
				(type default)
			)
			(layer "F.SilkS")
		)
		(fp_line
			(start -0.508 -0.9398)
			(end -0.508 0.9398)
			(stroke
				(width 0.1524)
				(type default)
			)
			(layer "F.SilkS")
		)
		(fp_rect
			(start -0.508 0.9398)
			(end 0.508 -0.9398)
			(stroke
				(width 0)
				(type default)
			)
			(fill no)
			(layer "F.CrtYd")
		)
		(fp_rect
			(start -0.508 0.9398)
			(end 0.508 -0.9398)
			(stroke
				(width 0)
				(type default)
			)
			(fill no)
			(layer "F.Fab")
		)
		(pad "1" smd custom
			(at 0 -0.4445 180)
			(size 0.1397 0.1397)
			(layers "F.Cu" "F.Mask" "F.Paste")
			(net "SSD_PRSNT_NET4")
			(options
				(clearance outline)
				(anchor circle)
			)
			(primitives
				(gr_poly
					(pts
						(arc
							(start -0.1778 -0.2794)
							(mid -0.249642 -0.249642)
							(end -0.2794 -0.1778)
						)
						(arc
							(start -0.2794 0.1778)
							(mid -0.249642 0.249642)
							(end -0.1778 0.2794)
						)
						(arc
							(start 0.1778 0.2794)
							(mid 0.249642 0.249642)
							(end 0.2794 0.1778)
						)
						(arc
							(start 0.2794 -0.1778)
							(mid 0.249642 -0.249642)
							(end 0.1778 -0.2794)
						)
					)
					(width 0)
					(fill yes)
				)
			)
		)
		(pad "2" smd custom
			(at 0 0.4445 180)
			(size 0.1397 0.1397)
			(layers "F.Cu" "F.Mask" "F.Paste")
			(net "SSD_PRSNT4")
			(options
				(clearance outline)
				(anchor circle)
			)
			(primitives
				(gr_poly
					(pts
						(arc
							(start -0.1778 -0.2794)
							(mid -0.249642 -0.249642)
							(end -0.2794 -0.1778)
						)
						(arc
							(start -0.2794 0.1778)
							(mid -0.249642 0.249642)
							(end -0.1778 0.2794)
						)
						(arc
							(start 0.1778 0.2794)
							(mid 0.249642 0.249642)
							(end 0.2794 0.1778)
						)
						(arc
							(start 0.2794 -0.1778)
							(mid 0.249642 -0.249642)
							(end 0.1778 -0.2794)
						)
					)
					(width 0)
					(fill yes)
				)
			)
		)
	)
	(footprint ""
		(layer "F.Cu")
		(at 36.7538 -315.8744 180)
		(property "Reference" "C393"
			(at 0 0 180)
			(layer "F.SilkS")
			(hide yes)
			(effects
				(font
					(size 1.27 1.27)
				)
			)
		)
		(property "Value" "SCD1U25V2KX-2-GP"
			(at 1.1811 -2.7051 180)
			(unlocked yes)
			(layer "F.Fab")
			(hide yes)
			(effects
				(font
					(size 1.016 1.016)
					(thickness 0.1524)
				)
			)
		)
		(property "Device Type" "C402H22"
			(at 1.1811 -4.2291 180)
			(unlocked yes)
			(layer "F.Fab")
			(hide yes)
			(effects
				(font
					(size 1.016 1.016)
					(thickness 0.1524)
				)
			)
		)
		(duplicate_pad_numbers_are_jumpers no)
		(fp_rect
			(start -0.4318 0.9525)
			(end 0.4318 -0.9525)
			(stroke
				(width 0)
				(type default)
			)
			(fill no)
			(layer "F.CrtYd")
		)
		(fp_rect
			(start -0.4318 0.9525)
			(end 0.4318 -0.9525)
			(stroke
				(width 0)
				(type default)
			)
			(fill no)
			(layer "F.Fab")
		)
		(pad "1" smd custom
			(at 0 -0.4445 180)
			(size 0.1524 0.1524)
			(layers "F.Cu" "F.Mask" "F.Paste")
			(net "P12V")
			(options
				(clearance outline)
				(anchor circle)
			)
			(primitives
				(gr_poly
					(pts
						(arc
							(start 0.3048 -0.2032)
							(mid 0.275042 -0.275042)
							(end 0.2032 -0.3048)
						)
						(arc
							(start -0.2032 -0.3048)
							(mid -0.275042 -0.275042)
							(end -0.3048 -0.2032)
						)
						(arc
							(start -0.3048 0.2032)
							(mid -0.275042 0.275042)
							(end -0.2032 0.3048)
						)
						(arc
							(start 0.2032 0.3048)
							(mid 0.275042 0.275042)
							(end 0.3048 0.2032)
						)
					)
					(width 0)
					(fill yes)
				)
			)
		)
		(pad "2" smd custom
			(at 0 0.4445 180)
			(size 0.1524 0.1524)
			(layers "F.Cu" "F.Mask" "F.Paste")
			(net "SW_SSD11_N")
			(options
				(clearance outline)
				(anchor circle)
			)
			(primitives
				(gr_poly
					(pts
						(arc
							(start 0.3048 -0.2032)
							(mid 0.275042 -0.275042)
							(end 0.2032 -0.3048)
						)
						(arc
							(start -0.2032 -0.3048)
							(mid -0.275042 -0.275042)
							(end -0.3048 -0.2032)
						)
						(arc
							(start -0.3048 0.2032)
							(mid -0.275042 0.275042)
							(end -0.2032 0.3048)
						)
						(arc
							(start 0.2032 0.3048)
							(mid 0.275042 0.275042)
							(end 0.3048 0.2032)
						)
					)
					(width 0)
					(fill yes)
				)
			)
		)
	)
	(footprint ""
		(layer "F.Cu")
		(at 80.264 -154.178)
		(property "Reference" "SR976"
			(at 0 0 0)
			(layer "F.SilkS")
			(hide yes)
			(effects
				(font
					(size 1.27 1.27)
				)
			)
		)
		(property "Value" "2KR2F-3-GP"
			(at 0.064008 -3.993896 0)
			(unlocked yes)
			(layer "F.Fab")
			(hide yes)
			(effects
				(font
					(size 1.016 1.016)
					(thickness 0.1524)
				)
			)
		)
		(property "Device Type" "R402H16"
			(at 0.064008 -5.517896 0)
			(unlocked yes)
			(layer "F.Fab")
			(hide yes)
			(effects
				(font
					(size 1.016 1.016)
					(thickness 0.1524)
				)
			)
		)
		(duplicate_pad_numbers_are_jumpers no)
		(fp_line
			(start -0.508 -0.9398)
			(end -0.508 0.9398)
			(stroke
				(width 0.1524)
				(type default)
			)
			(layer "F.SilkS")
		)
		(fp_line
			(start 0.508 -0.9398)
			(end -0.508 -0.9398)
			(stroke
				(width 0.1524)
				(type default)
			)
			(layer "F.SilkS")
		)
		(fp_rect
			(start -0.508 0.9398)
			(end 0.508 -0.9398)
			(stroke
				(width 0)
				(type default)
			)
			(fill no)
			(layer "F.CrtYd")
		)
		(fp_rect
			(start -0.508 0.9398)
			(end 0.508 -0.9398)
			(stroke
				(width 0)
				(type default)
			)
			(fill no)
			(layer "F.Fab")
		)
		(pad "1" smd custom
			(at 0 -0.4445)
			(size 0.1397 0.1397)
			(layers "F.Cu" "F.Mask" "F.Paste")
			(net "P3V3")
			(options
				(clearance outline)
				(anchor circle)
			)
			(primitives
				(gr_poly
					(pts
						(arc
							(start -0.1778 -0.2794)
							(mid -0.249642 -0.249642)
							(end -0.2794 -0.1778)
						)
						(arc
							(start -0.2794 0.1778)
							(mid -0.249642 0.249642)
							(end -0.1778 0.2794)
						)
						(arc
							(start 0.1778 0.2794)
							(mid 0.249642 0.249642)
							(end 0.2794 0.1778)
						)
						(arc
							(start 0.2794 -0.1778)
							(mid 0.249642 -0.249642)
							(end 0.1778 -0.2794)
						)
					)
					(width 0)
					(fill yes)
				)
			)
		)
		(pad "2" smd custom
			(at 0 0.4445)
			(size 0.1397 0.1397)
			(layers "F.Cu" "F.Mask" "F.Paste")
			(net "SDA_DR3")
			(options
				(clearance outline)
				(anchor circle)
			)
			(primitives
				(gr_poly
					(pts
						(arc
							(start -0.1778 -0.2794)
							(mid -0.249642 -0.249642)
							(end -0.2794 -0.1778)
						)
						(arc
							(start -0.2794 0.1778)
							(mid -0.249642 0.249642)
							(end -0.1778 0.2794)
						)
						(arc
							(start 0.1778 0.2794)
							(mid 0.249642 0.249642)
							(end 0.2794 0.1778)
						)
						(arc
							(start 0.2794 -0.1778)
							(mid 0.249642 -0.249642)
							(end 0.1778 -0.2794)
						)
					)
					(width 0)
					(fill yes)
				)
			)
		)
	)
	(footprint ""
		(layer "F.Cu")
		(at 87.757 -446.786 90)
		(property "Reference" "R9500"
			(at 0 0 90)
			(layer "F.SilkS")
			(hide yes)
			(effects
				(font
					(size 1.27 1.27)
				)
			)
		)
		(property "Value" "4K7R2J-2-GP"
			(at 0.064008 -3.993896 90)
			(unlocked yes)
			(layer "F.Fab")
			(hide yes)
			(effects
				(font
					(size 1.016 1.016)
					(thickness 0.1524)
				)
			)
		)
		(property "Device Type" "R402H16"
			(at 0.064008 -5.517896 90)
			(unlocked yes)
			(layer "F.Fab")
			(hide yes)
			(effects
				(font
					(size 1.016 1.016)
					(thickness 0.1524)
				)
			)
		)
		(duplicate_pad_numbers_are_jumpers no)
		(fp_line
			(start 0.508 -0.9398)
			(end -0.508 -0.9398)
			(stroke
				(width 0.1524)
				(type default)
			)
			(layer "F.SilkS")
		)
		(fp_line
			(start -0.508 -0.9398)
			(end -0.508 0.9398)
			(stroke
				(width 0.1524)
				(type default)
			)
			(layer "F.SilkS")
		)
		(fp_rect
			(start -0.508 0.9398)
			(end 0.508 -0.9398)
			(stroke
				(width 0)
				(type default)
			)
			(fill no)
			(layer "F.CrtYd")
		)
		(fp_rect
			(start -0.508 0.9398)
			(end 0.508 -0.9398)
			(stroke
				(width 0)
				(type default)
			)
			(fill no)
			(layer "F.Fab")
		)
		(pad "1" smd custom
			(at 0 -0.4445 90)
			(size 0.1397 0.1397)
			(layers "F.Cu" "F.Mask" "F.Paste")
			(net "P3V3")
			(options
				(clearance outline)
				(anchor circle)
			)
			(primitives
				(gr_poly
					(pts
						(arc
							(start -0.1778 -0.2794)
							(mid -0.249642 -0.249642)
							(end -0.2794 -0.1778)
						)
						(arc
							(start -0.2794 0.1778)
							(mid -0.249642 0.249642)
							(end -0.1778 0.2794)
						)
						(arc
							(start 0.1778 0.2794)
							(mid 0.249642 0.249642)
							(end 0.2794 0.1778)
						)
						(arc
							(start 0.2794 -0.1778)
							(mid 0.249642 -0.249642)
							(end 0.1778 -0.2794)
						)
					)
					(width 0)
					(fill yes)
				)
			)
		)
		(pad "2" smd custom
			(at 0 0.4445 90)
			(size 0.1397 0.1397)
			(layers "F.Cu" "F.Mask" "F.Paste")
			(net "SSD5_CLK0_OE_N")
			(options
				(clearance outline)
				(anchor circle)
			)
			(primitives
				(gr_poly
					(pts
						(arc
							(start -0.1778 -0.2794)
							(mid -0.249642 -0.249642)
							(end -0.2794 -0.1778)
						)
						(arc
							(start -0.2794 0.1778)
							(mid -0.249642 0.249642)
							(end -0.1778 0.2794)
						)
						(arc
							(start 0.1778 0.2794)
							(mid 0.249642 0.249642)
							(end 0.2794 0.1778)
						)
						(arc
							(start 0.2794 -0.1778)
							(mid 0.249642 -0.249642)
							(end 0.1778 -0.2794)
						)
					)
					(width 0)
					(fill yes)
				)
			)
		)
	)
	(footprint ""
		(layer "F.Cu")
		(at 88.011 -106.299)
		(property "Reference" "C8932"
			(at 0 0 0)
			(layer "F.SilkS")
			(hide yes)
			(effects
				(font
					(size 1.27 1.27)
				)
			)
		)
		(property "Value" "SCD1U16V2KX-3GP"
			(at 1.1811 -2.7051 0)
			(unlocked yes)
			(layer "F.Fab")
			(hide yes)
			(effects
				(font
					(size 1.016 1.016)
					(thickness 0.1524)
				)
			)
		)
		(property "Device Type" "C402H22"
			(at 1.1811 -4.2291 0)
			(unlocked yes)
			(layer "F.Fab")
			(hide yes)
			(effects
				(font
					(size 1.016 1.016)
					(thickness 0.1524)
				)
			)
		)
		(duplicate_pad_numbers_are_jumpers no)
		(fp_rect
			(start -0.4318 0.9525)
			(end 0.4318 -0.9525)
			(stroke
				(width 0)
				(type default)
			)
			(fill no)
			(layer "F.CrtYd")
		)
		(fp_rect
			(start -0.4318 0.9525)
			(end 0.4318 -0.9525)
			(stroke
				(width 0)
				(type default)
			)
			(fill no)
			(layer "F.Fab")
		)
		(pad "1" smd custom
			(at 0 -0.4445)
			(size 0.1524 0.1524)
			(layers "F.Cu" "F.Mask" "F.Paste")
			(net "VDDA_4")
			(options
				(clearance outline)
				(anchor circle)
			)
			(primitives
				(gr_poly
					(pts
						(arc
							(start 0.3048 -0.2032)
							(mid 0.275042 -0.275042)
							(end 0.2032 -0.3048)
						)
						(arc
							(start -0.2032 -0.3048)
							(mid -0.275042 -0.275042)
							(end -0.3048 -0.2032)
						)
						(arc
							(start -0.3048 0.2032)
							(mid -0.275042 0.275042)
							(end -0.2032 0.3048)
						)
						(arc
							(start 0.2032 0.3048)
							(mid 0.275042 0.275042)
							(end 0.3048 0.2032)
						)
					)
					(width 0)
					(fill yes)
				)
			)
		)
		(pad "2" smd custom
			(at 0 0.4445)
			(size 0.1524 0.1524)
			(layers "F.Cu" "F.Mask" "F.Paste")
			(net "GND")
			(options
				(clearance outline)
				(anchor circle)
			)
			(primitives
				(gr_poly
					(pts
						(arc
							(start 0.3048 -0.2032)
							(mid 0.275042 -0.275042)
							(end 0.2032 -0.3048)
						)
						(arc
							(start -0.2032 -0.3048)
							(mid -0.275042 -0.275042)
							(end -0.3048 -0.2032)
						)
						(arc
							(start -0.3048 0.2032)
							(mid -0.275042 0.275042)
							(end -0.2032 0.3048)
						)
						(arc
							(start 0.2032 0.3048)
							(mid 0.275042 0.275042)
							(end 0.3048 0.2032)
						)
					)
					(width 0)
					(fill yes)
				)
			)
		)
	)
	(footprint ""
		(layer "F.Cu")
		(at 225.552 -39.878 90)
		(property "Reference" "R9808"
			(at 0 0 90)
			(layer "F.SilkS")
			(hide yes)
			(effects
				(font
					(size 1.27 1.27)
				)
			)
		)
		(property "Value" "0R2J-2-GP"
			(at 0.064008 -3.993896 90)
			(unlocked yes)
			(layer "F.Fab")
			(hide yes)
			(effects
				(font
					(size 1.016 1.016)
					(thickness 0.1524)
				)
			)
		)
		(property "Device Type" "R402H16"
			(at 0.064008 -5.517896 90)
			(unlocked yes)
			(layer "F.Fab")
			(hide yes)
			(effects
				(font
					(size 1.016 1.016)
					(thickness 0.1524)
				)
			)
		)
		(duplicate_pad_numbers_are_jumpers no)
		(fp_line
			(start 0.508 -0.9398)
			(end -0.508 -0.9398)
			(stroke
				(width 0.1524)
				(type default)
			)
			(layer "F.SilkS")
		)
		(fp_line
			(start -0.508 -0.9398)
			(end -0.508 0.9398)
			(stroke
				(width 0.1524)
				(type default)
			)
			(layer "F.SilkS")
		)
		(fp_rect
			(start -0.508 0.9398)
			(end 0.508 -0.9398)
			(stroke
				(width 0)
				(type default)
			)
			(fill no)
			(layer "F.CrtYd")
		)
		(fp_rect
			(start -0.508 0.9398)
			(end 0.508 -0.9398)
			(stroke
				(width 0)
				(type default)
			)
			(fill no)
			(layer "F.Fab")
		)
		(pad "1" smd custom
			(at 0 -0.4445 90)
			(size 0.1397 0.1397)
			(layers "F.Cu" "F.Mask" "F.Paste")
			(net "ATTN_LED_DR4_R")
			(options
				(clearance outline)
				(anchor circle)
			)
			(primitives
				(gr_poly
					(pts
						(arc
							(start -0.1778 -0.2794)
							(mid -0.249642 -0.249642)
							(end -0.2794 -0.1778)
						)
						(arc
							(start -0.2794 0.1778)
							(mid -0.249642 0.249642)
							(end -0.1778 0.2794)
						)
						(arc
							(start 0.1778 0.2794)
							(mid 0.249642 0.249642)
							(end 0.2794 0.1778)
						)
						(arc
							(start 0.2794 -0.1778)
							(mid 0.249642 -0.249642)
							(end 0.1778 -0.2794)
						)
					)
					(width 0)
					(fill yes)
				)
			)
		)
		(pad "2" smd custom
			(at 0 0.4445 90)
			(size 0.1397 0.1397)
			(layers "F.Cu" "F.Mask" "F.Paste")
			(net "ATTN_LED_DR4_N")
			(options
				(clearance outline)
				(anchor circle)
			)
			(primitives
				(gr_poly
					(pts
						(arc
							(start -0.1778 -0.2794)
							(mid -0.249642 -0.249642)
							(end -0.2794 -0.1778)
						)
						(arc
							(start -0.2794 0.1778)
							(mid -0.249642 0.249642)
							(end -0.1778 0.2794)
						)
						(arc
							(start 0.1778 0.2794)
							(mid 0.249642 0.249642)
							(end 0.2794 0.1778)
						)
						(arc
							(start 0.2794 -0.1778)
							(mid 0.249642 -0.249642)
							(end 0.1778 -0.2794)
						)
					)
					(width 0)
					(fill yes)
				)
			)
		)
	)
)
